(kicad_pcb
	(version 20260206)
	(generator "pcbnew")
	(generator_version "10.0")
	(general
		(thickness 1.6)
		(legacy_teardrops no)
	)
	(paper "A4")
	(title_block
		(title "v1-chassis-manager — T6M_CM_d_v01_1031_1645.brd")
		(comment 1 "Open CloudServer (Microsoft) / footprints 2253-2262 of 2512")
	)
	(layers
		(0 "F.Cu" signal "TOP")
		(4 "In1.Cu" signal "GND1")
		(6 "In2.Cu" signal "IN1")
		(8 "In3.Cu" signal "VCC1")
		(10 "In4.Cu" signal "VCC2")
		(12 "In5.Cu" signal "GND2")
		(14 "In6.Cu" signal "IN2")
		(16 "In7.Cu" signal "IN3")
		(18 "In8.Cu" signal "GND3")
		(2 "B.Cu" signal "BOTTOM")
		(9 "F.Adhes" user "F.Adhesive")
		(11 "B.Adhes" user "B.Adhesive")
		(13 "F.Paste" user "Package Geometry/Pastemask Top")
		(15 "B.Paste" user "Package Geometry/Pastemask Bottom")
		(5 "F.SilkS" user "Ref Des/Silkscreen Top")
		(7 "B.SilkS" user "Ref Des/Silkscreen Bottom")
		(1 "F.Mask" user "Board Geometry/Soldermask Top")
		(3 "B.Mask" user "Board Geometry/Soldermask Bottom")
		(17 "Dwgs.User" user "User.Drawings")
		(19 "Cmts.User" user "User.Comments")
		(21 "Eco1.User" user "User.Eco1")
		(23 "Eco2.User" user "User.Eco2")
		(25 "Edge.Cuts" user "Board Geometry/Outline")
		(27 "Margin" user)
		(31 "F.CrtYd" user "Package Geometry/Place Bound Top")
		(29 "B.CrtYd" user "Package Geometry/Place Bound Bottom")
		(35 "F.Fab" user "Ref Des/Assembly Top")
		(33 "B.Fab" user "Ref Des/Assembly Bottom")
	)
	(footprint ""
		(layer "B.Cu")
		(at 146.322796 -59.96813 90)
		(property "Reference" "C339"
			(at 1.050036 -0.288798 270)
			(unlocked yes)
			(layer "B.SilkS")
			(effects
				(font
					(size 0.7874 0.5842)
					(thickness 0.1524)
				)
				(justify left mirror)
			)
		)
		(property "Value" ""
			(at 0 0 90)
			(layer "B.Fab")
			(effects
				(font
					(size 1.27 1.27)
				)
				(justify mirror)
			)
		)
		(duplicate_pad_numbers_are_jumpers no)
		(fp_line
			(start 0.7874 -0.4064)
			(end -0.7874 -0.4064)
			(stroke
				(width 0.1524)
				(type default)
			)
			(layer "B.SilkS")
		)
		(fp_line
			(start -0.7874 -0.4064)
			(end -0.7874 0.4064)
			(stroke
				(width 0.1524)
				(type default)
			)
			(layer "B.SilkS")
		)
		(fp_line
			(start 0 0.381)
			(end 0 -0.381)
			(stroke
				(width 0.1524)
				(type default)
			)
			(layer "B.SilkS")
		)
		(fp_line
			(start 0.7874 0.4064)
			(end 0.7874 -0.4064)
			(stroke
				(width 0.1524)
				(type default)
			)
			(layer "B.SilkS")
		)
		(fp_line
			(start -0.7874 0.4064)
			(end 0.7874 0.4064)
			(stroke
				(width 0.1524)
				(type default)
			)
			(layer "B.SilkS")
		)
		(fp_poly
			(pts
				(xy 0.5334 0.254) (xy 0.635 0.254) (xy 0.635 0.2286) (xy 0.635 -0.254) (xy 0.5334 -0.254) (xy 0.5334 -0.2794)
				(xy -0.5334 -0.2794) (xy -0.5334 -0.254) (xy -0.635 -0.254) (xy -0.635 0.254) (xy -0.5334 0.254)
				(xy -0.5334 0.2794) (xy 0.508 0.2794) (xy 0.5334 0.2794)
			)
			(stroke
				(width 0)
				(type default)
			)
			(fill no)
			(layer "B.CrtYd")
		)
		(pad "1" smd rect
			(at -0.40005 0 270)
			(size 0.4572 0.508)
			(layers "B.Cu" "B.Mask" "B.Paste")
			(net "P1V0_SATA")
		)
		(pad "2" smd rect
			(at 0.40005 0 270)
			(size 0.4572 0.508)
			(layers "B.Cu" "B.Mask" "B.Paste")
			(net "GND")
		)
	)
	(footprint ""
		(layer "B.Cu")
		(at 133.597396 -163.884356 180)
		(property "Reference" "R1309"
			(at -1.443228 -0.335534 270)
			(unlocked yes)
			(layer "B.SilkS")
			(effects
				(font
					(size 0.7874 0.5842)
					(thickness 0.1524)
				)
				(justify left mirror)
			)
		)
		(property "Value" ""
			(at 0 0 0)
			(layer "B.Fab")
			(effects
				(font
					(size 1.27 1.27)
				)
				(justify mirror)
			)
		)
		(duplicate_pad_numbers_are_jumpers no)
		(fp_line
			(start 0.7874 0.4064)
			(end 0.7874 -0.4064)
			(stroke
				(width 0.1524)
				(type default)
			)
			(layer "B.SilkS")
		)
		(fp_line
			(start 0.7874 -0.4064)
			(end -0.7874 -0.4064)
			(stroke
				(width 0.1524)
				(type default)
			)
			(layer "B.SilkS")
		)
		(fp_line
			(start -0.7874 0.4064)
			(end 0.7874 0.4064)
			(stroke
				(width 0.1524)
				(type default)
			)
			(layer "B.SilkS")
		)
		(fp_line
			(start -0.7874 -0.4064)
			(end -0.7874 0.4064)
			(stroke
				(width 0.1524)
				(type default)
			)
			(layer "B.SilkS")
		)
		(fp_poly
			(pts
				(xy 0.508 0.2794) (xy 0.508 0.2286) (xy 0.635 0.2286) (xy 0.635 -0.254) (xy 0.5334 -0.254) (xy 0.5334 -0.2794)
				(xy -0.5334 -0.2794) (xy -0.5334 -0.254) (xy -0.635 -0.254) (xy -0.635 0.254) (xy -0.5334 0.254)
				(xy -0.5334 0.2794)
			)
			(stroke
				(width 0)
				(type default)
			)
			(fill no)
			(layer "B.CrtYd")
		)
		(pad "1" smd rect
			(at -0.40005 0)
			(size 0.4572 0.508)
			(layers "B.Cu" "B.Mask" "B.Paste")
			(net "P3V3_NODE1")
		)
		(pad "2" smd rect
			(at 0.40005 0)
			(size 0.4572 0.508)
			(layers "B.Cu" "B.Mask" "B.Paste")
			(net "TACKOVER_EN")
		)
	)
	(footprint ""
		(layer "B.Cu")
		(at 61.702442 -178.6001 180)
		(property "Reference" "R686"
			(at -1.487678 1.11633 0)
			(unlocked yes)
			(layer "B.SilkS")
			(effects
				(font
					(size 0.7874 0.5842)
					(thickness 0.1524)
				)
				(justify left mirror)
			)
		)
		(property "Value" ""
			(at 0 0 0)
			(layer "B.Fab")
			(effects
				(font
					(size 1.27 1.27)
				)
				(justify mirror)
			)
		)
		(duplicate_pad_numbers_are_jumpers no)
		(fp_line
			(start 0.7874 0.4064)
			(end 0.7874 -0.4064)
			(stroke
				(width 0.1524)
				(type default)
			)
			(layer "B.SilkS")
		)
		(fp_line
			(start 0.7874 -0.4064)
			(end -0.7874 -0.4064)
			(stroke
				(width 0.1524)
				(type default)
			)
			(layer "B.SilkS")
		)
		(fp_line
			(start -0.7874 0.4064)
			(end 0.7874 0.4064)
			(stroke
				(width 0.1524)
				(type default)
			)
			(layer "B.SilkS")
		)
		(fp_line
			(start -0.7874 -0.4064)
			(end -0.7874 0.4064)
			(stroke
				(width 0.1524)
				(type default)
			)
			(layer "B.SilkS")
		)
		(fp_poly
			(pts
				(xy 0.508 0.2794) (xy 0.508 0.2286) (xy 0.635 0.2286) (xy 0.635 -0.254) (xy 0.5334 -0.254) (xy 0.5334 -0.2794)
				(xy -0.5334 -0.2794) (xy -0.5334 -0.254) (xy -0.635 -0.254) (xy -0.635 0.254) (xy -0.5334 0.254)
				(xy -0.5334 0.2794)
			)
			(stroke
				(width 0)
				(type default)
			)
			(fill no)
			(layer "B.CrtYd")
		)
		(pad "1" smd rect
			(at -0.40005 0)
			(size 0.4572 0.508)
			(layers "B.Cu" "B.Mask" "B.Paste")
			(net "P3V3_NODE1")
		)
		(pad "2" smd rect
			(at 0.40005 0)
			(size 0.4572 0.508)
			(layers "B.Cu" "B.Mask" "B.Paste")
			(net "N21700864")
		)
	)
	(footprint ""
		(layer "B.Cu")
		(at 141.233652 -138.23315)
		(property "Reference" "C890"
			(at 3.977894 -3.295142 0)
			(unlocked yes)
			(layer "B.SilkS")
			(effects
				(font
					(size 0.7874 0.5842)
					(thickness 0.1524)
				)
				(justify left mirror)
			)
		)
		(property "Value" ""
			(at 0 0 0)
			(layer "B.Fab")
			(effects
				(font
					(size 1.27 1.27)
				)
				(justify mirror)
			)
		)
		(duplicate_pad_numbers_are_jumpers no)
		(fp_line
			(start -0.7874 -0.4064)
			(end -0.7874 0.4064)
			(stroke
				(width 0.1524)
				(type default)
			)
			(layer "B.SilkS")
		)
		(fp_line
			(start -0.7874 0.4064)
			(end 0.7874 0.4064)
			(stroke
				(width 0.1524)
				(type default)
			)
			(layer "B.SilkS")
		)
		(fp_line
			(start 0 0.381)
			(end 0 -0.381)
			(stroke
				(width 0.1524)
				(type default)
			)
			(layer "B.SilkS")
		)
		(fp_line
			(start 0.7874 -0.4064)
			(end -0.7874 -0.4064)
			(stroke
				(width 0.1524)
				(type default)
			)
			(layer "B.SilkS")
		)
		(fp_line
			(start 0.7874 0.4064)
			(end 0.7874 -0.4064)
			(stroke
				(width 0.1524)
				(type default)
			)
			(layer "B.SilkS")
		)
		(fp_poly
			(pts
				(xy 0.5334 0.254) (xy 0.635 0.254) (xy 0.635 0.2286) (xy 0.635 -0.254) (xy 0.5334 -0.254) (xy 0.5334 -0.2794)
				(xy -0.5334 -0.2794) (xy -0.5334 -0.254) (xy -0.635 -0.254) (xy -0.635 0.254) (xy -0.5334 0.254)
				(xy -0.5334 0.2794) (xy 0.508 0.2794) (xy 0.5334 0.2794)
			)
			(stroke
				(width 0)
				(type default)
			)
			(fill no)
			(layer "B.CrtYd")
		)
		(pad "1" smd rect
			(at -0.40005 0 180)
			(size 0.4572 0.508)
			(layers "B.Cu" "B.Mask" "B.Paste")
			(net "P1V0_NODE1")
		)
		(pad "2" smd rect
			(at 0.40005 0 180)
			(size 0.4572 0.508)
			(layers "B.Cu" "B.Mask" "B.Paste")
			(net "GND")
		)
	)
	(footprint ""
		(layer "B.Cu")
		(at 76.7461 -163.120832 180)
		(property "Reference" "R793"
			(at 2.647188 -0.339852 0)
			(unlocked yes)
			(layer "B.SilkS")
			(effects
				(font
					(size 0.7874 0.5842)
					(thickness 0.1524)
				)
				(justify left mirror)
			)
		)
		(property "Value" ""
			(at 0 0 0)
			(layer "B.Fab")
			(effects
				(font
					(size 1.27 1.27)
				)
				(justify mirror)
			)
		)
		(duplicate_pad_numbers_are_jumpers no)
		(fp_line
			(start 0.7874 0.4064)
			(end 0.7874 -0.4064)
			(stroke
				(width 0.1524)
				(type default)
			)
			(layer "B.SilkS")
		)
		(fp_line
			(start 0.7874 -0.4064)
			(end -0.7874 -0.4064)
			(stroke
				(width 0.1524)
				(type default)
			)
			(layer "B.SilkS")
		)
		(fp_line
			(start -0.7874 0.4064)
			(end 0.7874 0.4064)
			(stroke
				(width 0.1524)
				(type default)
			)
			(layer "B.SilkS")
		)
		(fp_line
			(start -0.7874 -0.4064)
			(end -0.7874 0.4064)
			(stroke
				(width 0.1524)
				(type default)
			)
			(layer "B.SilkS")
		)
		(fp_poly
			(pts
				(xy 0.508 0.2794) (xy 0.508 0.2286) (xy 0.635 0.2286) (xy 0.635 -0.254) (xy 0.5334 -0.254) (xy 0.5334 -0.2794)
				(xy -0.5334 -0.2794) (xy -0.5334 -0.254) (xy -0.635 -0.254) (xy -0.635 0.254) (xy -0.5334 0.254)
				(xy -0.5334 0.2794)
			)
			(stroke
				(width 0)
				(type default)
			)
			(fill no)
			(layer "B.CrtYd")
		)
		(pad "1" smd rect
			(at -0.40005 0)
			(size 0.4572 0.508)
			(layers "B.Cu" "B.Mask" "B.Paste")
			(net "CPLD_WDT2_R")
		)
		(pad "2" smd rect
			(at 0.40005 0)
			(size 0.4572 0.508)
			(layers "B.Cu" "B.Mask" "B.Paste")
			(net "P3V3_NODE1")
		)
	)
	(footprint ""
		(layer "B.Cu")
		(at 153.604214 -64.971422 -90)
		(property "Reference" "C344"
			(at 2.01422 -5.923026 270)
			(unlocked yes)
			(layer "B.SilkS")
			(effects
				(font
					(size 0.7874 0.5842)
					(thickness 0.1524)
				)
				(justify left mirror)
			)
		)
		(property "Value" ""
			(at 0 0 90)
			(layer "B.Fab")
			(effects
				(font
					(size 1.27 1.27)
				)
				(justify mirror)
			)
		)
		(duplicate_pad_numbers_are_jumpers no)
		(fp_line
			(start -0.7874 0.4064)
			(end 0.7874 0.4064)
			(stroke
				(width 0.1524)
				(type default)
			)
			(layer "B.SilkS")
		)
		(fp_line
			(start 0.7874 0.4064)
			(end 0.7874 -0.4064)
			(stroke
				(width 0.1524)
				(type default)
			)
			(layer "B.SilkS")
		)
		(fp_line
			(start 0 0.381)
			(end 0 -0.381)
			(stroke
				(width 0.1524)
				(type default)
			)
			(layer "B.SilkS")
		)
		(fp_line
			(start -0.7874 -0.4064)
			(end -0.7874 0.4064)
			(stroke
				(width 0.1524)
				(type default)
			)
			(layer "B.SilkS")
		)
		(fp_line
			(start 0.7874 -0.4064)
			(end -0.7874 -0.4064)
			(stroke
				(width 0.1524)
				(type default)
			)
			(layer "B.SilkS")
		)
		(fp_poly
			(pts
				(xy 0.5334 0.254) (xy 0.635 0.254) (xy 0.635 0.2286) (xy 0.635 -0.254) (xy 0.5334 -0.254) (xy 0.5334 -0.2794)
				(xy -0.5334 -0.2794) (xy -0.5334 -0.254) (xy -0.635 -0.254) (xy -0.635 0.254) (xy -0.5334 0.254)
				(xy -0.5334 0.2794) (xy 0.508 0.2794) (xy 0.5334 0.2794)
			)
			(stroke
				(width 0)
				(type default)
			)
			(fill no)
			(layer "B.CrtYd")
		)
		(pad "1" smd rect
			(at -0.40005 0 90)
			(size 0.4572 0.508)
			(layers "B.Cu" "B.Mask" "B.Paste")
			(net "P1V8_SATA_VAA2_0_NODE1")
		)
		(pad "2" smd rect
			(at 0.40005 0 90)
			(size 0.4572 0.508)
			(layers "B.Cu" "B.Mask" "B.Paste")
			(net "GND")
		)
	)
	(footprint ""
		(layer "B.Cu")
		(at 134.22376 -187.872624 -90)
		(property "Reference" "C722"
			(at -4.565396 1.361948 270)
			(unlocked yes)
			(layer "B.SilkS")
			(effects
				(font
					(size 0.7874 0.5842)
					(thickness 0.1524)
				)
				(justify left mirror)
			)
		)
		(property "Value" ""
			(at 0 0 90)
			(layer "B.Fab")
			(effects
				(font
					(size 1.27 1.27)
				)
				(justify mirror)
			)
		)
		(duplicate_pad_numbers_are_jumpers no)
		(fp_line
			(start -0.7874 0.4064)
			(end 0.7874 0.4064)
			(stroke
				(width 0.1524)
				(type default)
			)
			(layer "B.SilkS")
		)
		(fp_line
			(start 0.7874 0.4064)
			(end 0.7874 -0.4064)
			(stroke
				(width 0.1524)
				(type default)
			)
			(layer "B.SilkS")
		)
		(fp_line
			(start 0 0.381)
			(end 0 -0.381)
			(stroke
				(width 0.1524)
				(type default)
			)
			(layer "B.SilkS")
		)
		(fp_line
			(start -0.7874 -0.4064)
			(end -0.7874 0.4064)
			(stroke
				(width 0.1524)
				(type default)
			)
			(layer "B.SilkS")
		)
		(fp_line
			(start 0.7874 -0.4064)
			(end -0.7874 -0.4064)
			(stroke
				(width 0.1524)
				(type default)
			)
			(layer "B.SilkS")
		)
		(fp_poly
			(pts
				(xy 0.5334 0.254) (xy 0.635 0.254) (xy 0.635 0.2286) (xy 0.635 -0.254) (xy 0.5334 -0.254) (xy 0.5334 -0.2794)
				(xy -0.5334 -0.2794) (xy -0.5334 -0.254) (xy -0.635 -0.254) (xy -0.635 0.254) (xy -0.5334 0.254)
				(xy -0.5334 0.2794) (xy 0.508 0.2794) (xy 0.5334 0.2794)
			)
			(stroke
				(width 0)
				(type default)
			)
			(fill no)
			(layer "B.CrtYd")
		)
		(pad "1" smd rect
			(at -0.40005 0 90)
			(size 0.4572 0.508)
			(layers "B.Cu" "B.Mask" "B.Paste")
			(net "UART_T9_NODE1_TXD_R")
		)
		(pad "2" smd rect
			(at 0.40005 0 90)
			(size 0.4572 0.508)
			(layers "B.Cu" "B.Mask" "B.Paste")
			(net "GND")
		)
	)
	(footprint ""
		(layer "B.Cu")
		(at 141.589252 -46.487842)
		(property "Reference" "C481"
			(at 3.907028 -0.084836 0)
			(unlocked yes)
			(layer "B.SilkS")
			(effects
				(font
					(size 0.7874 0.5842)
					(thickness 0.1524)
				)
				(justify left mirror)
			)
		)
		(property "Value" ""
			(at 0 0 0)
			(layer "B.Fab")
			(effects
				(font
					(size 1.27 1.27)
				)
				(justify mirror)
			)
		)
		(duplicate_pad_numbers_are_jumpers no)
		(fp_line
			(start -0.7874 -0.4064)
			(end -0.7874 0.4064)
			(stroke
				(width 0.1524)
				(type default)
			)
			(layer "B.SilkS")
		)
		(fp_line
			(start -0.7874 0.4064)
			(end 0.7874 0.4064)
			(stroke
				(width 0.1524)
				(type default)
			)
			(layer "B.SilkS")
		)
		(fp_line
			(start 0 0.381)
			(end 0 -0.381)
			(stroke
				(width 0.1524)
				(type default)
			)
			(layer "B.SilkS")
		)
		(fp_line
			(start 0.7874 -0.4064)
			(end -0.7874 -0.4064)
			(stroke
				(width 0.1524)
				(type default)
			)
			(layer "B.SilkS")
		)
		(fp_line
			(start 0.7874 0.4064)
			(end 0.7874 -0.4064)
			(stroke
				(width 0.1524)
				(type default)
			)
			(layer "B.SilkS")
		)
		(fp_poly
			(pts
				(xy 0.5334 0.254) (xy 0.635 0.254) (xy 0.635 0.2286) (xy 0.635 -0.254) (xy 0.5334 -0.254) (xy 0.5334 -0.2794)
				(xy -0.5334 -0.2794) (xy -0.5334 -0.254) (xy -0.635 -0.254) (xy -0.635 0.254) (xy -0.5334 0.254)
				(xy -0.5334 0.2794) (xy 0.508 0.2794) (xy 0.5334 0.2794)
			)
			(stroke
				(width 0)
				(type default)
			)
			(fill no)
			(layer "B.CrtYd")
		)
		(pad "1" smd rect
			(at -0.40005 0 180)
			(size 0.4572 0.508)
			(layers "B.Cu" "B.Mask" "B.Paste")
			(net "P5V_NODE1")
		)
		(pad "2" smd rect
			(at 0.40005 0 180)
			(size 0.4572 0.508)
			(layers "B.Cu" "B.Mask" "B.Paste")
			(net "GND")
		)
	)
	(footprint ""
		(layer "B.Cu")
		(at 120.596914 -166.805102)
		(property "Reference" "R1211"
			(at 0.773938 -2.74447 0)
			(unlocked yes)
			(layer "B.SilkS")
			(effects
				(font
					(size 0.7874 0.5842)
					(thickness 0.1524)
				)
				(justify left mirror)
			)
		)
		(property "Value" ""
			(at 0 0 0)
			(layer "B.Fab")
			(effects
				(font
					(size 1.27 1.27)
				)
				(justify mirror)
			)
		)
		(duplicate_pad_numbers_are_jumpers no)
		(fp_line
			(start -0.7874 -0.4064)
			(end -0.7874 0.4064)
			(stroke
				(width 0.1524)
				(type default)
			)
			(layer "B.SilkS")
		)
		(fp_line
			(start -0.7874 0.4064)
			(end 0.7874 0.4064)
			(stroke
				(width 0.1524)
				(type default)
			)
			(layer "B.SilkS")
		)
		(fp_line
			(start 0.7874 -0.4064)
			(end -0.7874 -0.4064)
			(stroke
				(width 0.1524)
				(type default)
			)
			(layer "B.SilkS")
		)
		(fp_line
			(start 0.7874 0.4064)
			(end 0.7874 -0.4064)
			(stroke
				(width 0.1524)
				(type default)
			)
			(layer "B.SilkS")
		)
		(fp_poly
			(pts
				(xy 0.508 0.2794) (xy 0.508 0.2286) (xy 0.635 0.2286) (xy 0.635 -0.254) (xy 0.5334 -0.254) (xy 0.5334 -0.2794)
				(xy -0.5334 -0.2794) (xy -0.5334 -0.254) (xy -0.635 -0.254) (xy -0.635 0.254) (xy -0.5334 0.254)
				(xy -0.5334 0.2794)
			)
			(stroke
				(width 0)
				(type default)
			)
			(fill no)
			(layer "B.CrtYd")
		)
		(pad "1" smd rect
			(at -0.40005 0 180)
			(size 0.4572 0.508)
			(layers "B.Cu" "B.Mask" "B.Paste")
			(net "FAN_MAX_CTRL")
		)
		(pad "2" smd rect
			(at 0.40005 0 180)
			(size 0.4572 0.508)
			(layers "B.Cu" "B.Mask" "B.Paste")
			(net "P3V3_NODE1")
		)
	)
	(footprint ""
		(layer "B.Cu")
		(at 110.72876 -188.126624 -90)
		(property "Reference" "C733"
			(at -4.080256 -0.71755 270)
			(unlocked yes)
			(layer "B.SilkS")
			(effects
				(font
					(size 0.7874 0.5842)
					(thickness 0.1524)
				)
				(justify left mirror)
			)
		)
		(property "Value" ""
			(at 0 0 90)
			(layer "B.Fab")
			(effects
				(font
					(size 1.27 1.27)
				)
				(justify mirror)
			)
		)
		(duplicate_pad_numbers_are_jumpers no)
		(fp_line
			(start -0.7874 0.4064)
			(end 0.7874 0.4064)
			(stroke
				(width 0.1524)
				(type default)
			)
			(layer "B.SilkS")
		)
		(fp_line
			(start 0.7874 0.4064)
			(end 0.7874 -0.4064)
			(stroke
				(width 0.1524)
				(type default)
			)
			(layer "B.SilkS")
		)
		(fp_line
			(start 0 0.381)
			(end 0 -0.381)
			(stroke
				(width 0.1524)
				(type default)
			)
			(layer "B.SilkS")
		)
		(fp_line
			(start -0.7874 -0.4064)
			(end -0.7874 0.4064)
			(stroke
				(width 0.1524)
				(type default)
			)
			(layer "B.SilkS")
		)
		(fp_line
			(start 0.7874 -0.4064)
			(end -0.7874 -0.4064)
			(stroke
				(width 0.1524)
				(type default)
			)
			(layer "B.SilkS")
		)
		(fp_poly
			(pts
				(xy 0.5334 0.254) (xy 0.635 0.254) (xy 0.635 0.2286) (xy 0.635 -0.254) (xy 0.5334 -0.254) (xy 0.5334 -0.2794)
				(xy -0.5334 -0.2794) (xy -0.5334 -0.254) (xy -0.635 -0.254) (xy -0.635 0.254) (xy -0.5334 0.254)
				(xy -0.5334 0.2794) (xy 0.508 0.2794) (xy 0.5334 0.2794)
			)
			(stroke
				(width 0)
				(type default)
			)
			(fill no)
			(layer "B.CrtYd")
		)
		(pad "1" smd rect
			(at -0.40005 0 90)
			(size 0.4572 0.508)
			(layers "B.Cu" "B.Mask" "B.Paste")
			(net "UART_T7_NODE3_TXD_R")
		)
		(pad "2" smd rect
			(at 0.40005 0 90)
			(size 0.4572 0.508)
			(layers "B.Cu" "B.Mask" "B.Paste")
			(net "GND")
		)
	)
)
